(kicad_pcb
	(version 20260206)
	(generator "pcbnew")
	(generator_version "10.0")
	(general
		(thickness 1.6)
		(legacy_teardrops no)
	)
	(paper "A4")
	(title_block
		(title "03242023_DA0F0TMBIJ0_F0T_Motherboard_J_brd_V01_OCP.brd")
		(comment 1 "Grand Teton / footprints 4242-4248 of 6105")
	)
	(layers
		(0 "F.Cu" signal "TOP")
		(4 "In1.Cu" signal "GND")
		(6 "In2.Cu" signal "IN1")
		(8 "In3.Cu" signal "GND1")
		(10 "In4.Cu" signal "IN2")
		(12 "In5.Cu" signal "GND2")
		(14 "In6.Cu" signal "IN3")
		(16 "In7.Cu" signal "GND3")
		(18 "In8.Cu" signal "VCC")
		(20 "In9.Cu" signal "VCC1")
		(22 "In10.Cu" signal "GND4")
		(24 "In11.Cu" signal "IN4")
		(26 "In12.Cu" signal "GND5")
		(28 "In13.Cu" signal "IN5")
		(30 "In14.Cu" signal "GND6")
		(32 "In15.Cu" signal "IN6")
		(34 "In16.Cu" signal "GND7")
		(2 "B.Cu" signal "BOTTOM")
		(9 "F.Adhes" user "F.Adhesive")
		(11 "B.Adhes" user "B.Adhesive")
		(13 "F.Paste" user "Package Geometry/Pastemask Top")
		(15 "B.Paste" user "Package Geometry/Pastemask Bottom")
		(5 "F.SilkS" user "Ref Des/Silkscreen Top")
		(7 "B.SilkS" user "Ref Des/Silkscreen Bottom")
		(1 "F.Mask" user "Board Geometry/Soldermask Top")
		(3 "B.Mask" user "Board Geometry/Soldermask Bottom")
		(17 "Dwgs.User" user "User.Drawings")
		(19 "Cmts.User" user "User.Comments")
		(21 "Eco1.User" user "User.Eco1")
		(23 "Eco2.User" user "User.Eco2")
		(25 "Edge.Cuts" user "Board Geometry/Outline")
		(27 "Margin" user)
		(31 "F.CrtYd" user "Package Geometry/Place Bound Top")
		(29 "B.CrtYd" user "Package Geometry/Place Bound Bottom")
		(35 "F.Fab" user "Ref Des/Assembly Top")
		(33 "B.Fab" user "Ref Des/Assembly Bottom")
	)
	(footprint ""
		(layer "B.Cu")
		(at 369.49888 -46.192948 180)
		(property "Reference" "R4114"
			(at 0 0 0)
			(layer "B.SilkS")
			(hide yes)
			(effects
				(font
					(size 1.27 1.27)
				)
				(justify mirror)
			)
		)
		(property "Value" ""
			(at 0 0 0)
			(layer "B.Fab")
			(effects
				(font
					(size 1.27 1.27)
				)
				(justify mirror)
			)
		)
		(duplicate_pad_numbers_are_jumpers no)
		(fp_line
			(start 0.7874 0.4064)
			(end 0.7874 -0.4064)
			(stroke
				(width 0.1524)
				(type default)
			)
			(layer "B.SilkS")
		)
		(fp_line
			(start 0.7874 -0.4064)
			(end -0.7874 -0.4064)
			(stroke
				(width 0.1524)
				(type default)
			)
			(layer "B.SilkS")
		)
		(fp_line
			(start -0.7874 0.4064)
			(end 0.7874 0.4064)
			(stroke
				(width 0.1524)
				(type default)
			)
			(layer "B.SilkS")
		)
		(fp_line
			(start -0.7874 -0.4064)
			(end -0.7874 0.4064)
			(stroke
				(width 0.1524)
				(type default)
			)
			(layer "B.SilkS")
		)
		(fp_line
			(start 0.67945 0.3048)
			(end 0.67945 -0.305054)
			(stroke
				(width 0.1)
				(type default)
			)
			(layer "B.Fab")
		)
		(fp_line
			(start 0.67945 -0.305054)
			(end 0.12065 -0.305054)
			(stroke
				(width 0.1)
				(type default)
			)
			(layer "B.Fab")
		)
		(fp_line
			(start 0.12065 0.3048)
			(end 0.67945 0.3048)
			(stroke
				(width 0.1)
				(type default)
			)
			(layer "B.Fab")
		)
		(fp_line
			(start 0.12065 0.2794)
			(end 0.12065 0.3048)
			(stroke
				(width 0.1)
				(type default)
			)
			(layer "B.Fab")
		)
		(fp_line
			(start 0.12065 -0.2794)
			(end -0.12065 -0.2794)
			(stroke
				(width 0.1)
				(type default)
			)
			(layer "B.Fab")
		)
		(fp_line
			(start 0.12065 -0.305054)
			(end 0.12065 -0.2794)
			(stroke
				(width 0.1)
				(type default)
			)
			(layer "B.Fab")
		)
		(fp_line
			(start -0.120396 0.3048)
			(end -0.120396 0.2794)
			(stroke
				(width 0.1)
				(type default)
			)
			(layer "B.Fab")
		)
		(fp_line
			(start -0.120396 0.2794)
			(end 0.12065 0.2794)
			(stroke
				(width 0.1)
				(type default)
			)
			(layer "B.Fab")
		)
		(fp_line
			(start -0.12065 -0.2794)
			(end -0.12065 -0.3048)
			(stroke
				(width 0.1)
				(type default)
			)
			(layer "B.Fab")
		)
		(fp_line
			(start -0.12065 -0.3048)
			(end -0.67945 -0.3048)
			(stroke
				(width 0.1)
				(type default)
			)
			(layer "B.Fab")
		)
		(fp_line
			(start -0.67945 0.3048)
			(end -0.120396 0.3048)
			(stroke
				(width 0.1)
				(type default)
			)
			(layer "B.Fab")
		)
		(fp_line
			(start -0.67945 -0.3048)
			(end -0.67945 0.3048)
			(stroke
				(width 0.1)
				(type default)
			)
			(layer "B.Fab")
		)
		(pad "1" smd circle
			(at 0.40005 0)
			(size 0 0)
			(layers "B.Cu" "B.Mask" "B.Paste")
			(net "PD_PCH_GPP_E_10")
		)
		(pad "2" smd circle
			(at -0.40005 0)
			(size 0 0)
			(layers "B.Cu" "B.Mask" "B.Paste")
			(net "GND")
		)
	)
	(footprint ""
		(layer "B.Cu")
		(at 321.206622 -36.185348 45)
		(property "Reference" "R1995"
			(at 0 0 45)
			(layer "B.SilkS")
			(hide yes)
			(effects
				(font
					(size 1.27 1.27)
				)
				(justify mirror)
			)
		)
		(property "Value" ""
			(at 0 0 45)
			(layer "B.Fab")
			(effects
				(font
					(size 1.27 1.27)
				)
				(justify mirror)
			)
		)
		(duplicate_pad_numbers_are_jumpers no)
		(fp_line
			(start -0.787389 -0.406267)
			(end -0.787389 0.406267)
			(stroke
				(width 0.1524)
				(type default)
			)
			(layer "B.SilkS")
		)
		(fp_line
			(start -0.787389 0.406267)
			(end 0.787389 0.406267)
			(stroke
				(width 0.1524)
				(type default)
			)
			(layer "B.SilkS")
		)
		(fp_line
			(start 0.787389 -0.406267)
			(end -0.787389 -0.406267)
			(stroke
				(width 0.1524)
				(type default)
			)
			(layer "B.SilkS")
		)
		(fp_line
			(start 0.787389 0.406267)
			(end 0.787389 -0.406267)
			(stroke
				(width 0.1524)
				(type default)
			)
			(layer "B.SilkS")
		)
		(fp_line
			(start -0.679446 -0.30479)
			(end -0.679446 0.30479)
			(stroke
				(width 0.1)
				(type default)
			)
			(layer "B.Fab")
		)
		(fp_line
			(start -0.120515 -0.30479)
			(end -0.679446 -0.30479)
			(stroke
				(width 0.1)
				(type default)
			)
			(layer "B.Fab")
		)
		(fp_line
			(start -0.120695 -0.279466)
			(end -0.120515 -0.30479)
			(stroke
				(width 0.1)
				(type default)
			)
			(layer "B.Fab")
		)
		(fp_line
			(start -0.679446 0.30479)
			(end -0.120515 0.30479)
			(stroke
				(width 0.1)
				(type default)
			)
			(layer "B.Fab")
		)
		(fp_line
			(start 0.120695 -0.304969)
			(end 0.120695 -0.279466)
			(stroke
				(width 0.1)
				(type default)
			)
			(layer "B.Fab")
		)
		(fp_line
			(start 0.120695 -0.279466)
			(end -0.120695 -0.279466)
			(stroke
				(width 0.1)
				(type default)
			)
			(layer "B.Fab")
		)
		(fp_line
			(start -0.120335 0.279466)
			(end 0.120695 0.279466)
			(stroke
				(width 0.1)
				(type default)
			)
			(layer "B.Fab")
		)
		(fp_line
			(start -0.120515 0.30479)
			(end -0.120335 0.279466)
			(stroke
				(width 0.1)
				(type default)
			)
			(layer "B.Fab")
		)
		(fp_line
			(start 0.679446 -0.305149)
			(end 0.120695 -0.304969)
			(stroke
				(width 0.1)
				(type default)
			)
			(layer "B.Fab")
		)
		(fp_line
			(start 0.120695 0.279466)
			(end 0.120515 0.30479)
			(stroke
				(width 0.1)
				(type default)
			)
			(layer "B.Fab")
		)
		(fp_line
			(start 0.120515 0.30479)
			(end 0.679446 0.30479)
			(stroke
				(width 0.1)
				(type default)
			)
			(layer "B.Fab")
		)
		(fp_line
			(start 0.679446 0.30479)
			(end 0.679446 -0.305149)
			(stroke
				(width 0.1)
				(type default)
			)
			(layer "B.Fab")
		)
		(pad "1" smd circle
			(at 0.40005 0 225)
			(size 0 0)
			(layers "B.Cu" "B.Mask" "B.Paste")
			(net "FM_PCH_SLP_S3_N")
		)
		(pad "2" smd circle
			(at -0.40005 0 225)
			(size 0 0)
			(layers "B.Cu" "B.Mask" "B.Paste")
			(net "FM_SLPS3_PLD_N")
		)
	)
	(footprint ""
		(layer "B.Cu")
		(at 293.544498 -403.031452 90)
		(property "Reference" "PR2513"
			(at 0 0 90)
			(layer "B.SilkS")
			(hide yes)
			(effects
				(font
					(size 1.27 1.27)
				)
				(justify mirror)
			)
		)
		(property "Value" ""
			(at 0 0 90)
			(layer "B.Fab")
			(effects
				(font
					(size 1.27 1.27)
				)
				(justify mirror)
			)
		)
		(duplicate_pad_numbers_are_jumpers no)
		(fp_line
			(start 0.7874 -0.4064)
			(end -0.7874 -0.4064)
			(stroke
				(width 0.1524)
				(type default)
			)
			(layer "B.SilkS")
		)
		(fp_line
			(start -0.7874 -0.4064)
			(end -0.7874 0.4064)
			(stroke
				(width 0.1524)
				(type default)
			)
			(layer "B.SilkS")
		)
		(fp_line
			(start 0.7874 0.4064)
			(end 0.7874 -0.4064)
			(stroke
				(width 0.1524)
				(type default)
			)
			(layer "B.SilkS")
		)
		(fp_line
			(start -0.7874 0.4064)
			(end 0.7874 0.4064)
			(stroke
				(width 0.1524)
				(type default)
			)
			(layer "B.SilkS")
		)
		(fp_line
			(start 0.67945 -0.305054)
			(end 0.12065 -0.305054)
			(stroke
				(width 0.1)
				(type default)
			)
			(layer "B.Fab")
		)
		(fp_line
			(start 0.12065 -0.305054)
			(end 0.12065 -0.2794)
			(stroke
				(width 0.1)
				(type default)
			)
			(layer "B.Fab")
		)
		(fp_line
			(start -0.12065 -0.3048)
			(end -0.67945 -0.3048)
			(stroke
				(width 0.1)
				(type default)
			)
			(layer "B.Fab")
		)
		(fp_line
			(start -0.67945 -0.3048)
			(end -0.67945 0.3048)
			(stroke
				(width 0.1)
				(type default)
			)
			(layer "B.Fab")
		)
		(fp_line
			(start 0.12065 -0.2794)
			(end -0.12065 -0.2794)
			(stroke
				(width 0.1)
				(type default)
			)
			(layer "B.Fab")
		)
		(fp_line
			(start -0.12065 -0.2794)
			(end -0.12065 -0.3048)
			(stroke
				(width 0.1)
				(type default)
			)
			(layer "B.Fab")
		)
		(fp_line
			(start 0.12065 0.2794)
			(end 0.12065 0.3048)
			(stroke
				(width 0.1)
				(type default)
			)
			(layer "B.Fab")
		)
		(fp_line
			(start -0.120396 0.2794)
			(end 0.12065 0.2794)
			(stroke
				(width 0.1)
				(type default)
			)
			(layer "B.Fab")
		)
		(fp_line
			(start 0.67945 0.3048)
			(end 0.67945 -0.305054)
			(stroke
				(width 0.1)
				(type default)
			)
			(layer "B.Fab")
		)
		(fp_line
			(start 0.12065 0.3048)
			(end 0.67945 0.3048)
			(stroke
				(width 0.1)
				(type default)
			)
			(layer "B.Fab")
		)
		(fp_line
			(start -0.120396 0.3048)
			(end -0.120396 0.2794)
			(stroke
				(width 0.1)
				(type default)
			)
			(layer "B.Fab")
		)
		(fp_line
			(start -0.67945 0.3048)
			(end -0.120396 0.3048)
			(stroke
				(width 0.1)
				(type default)
			)
			(layer "B.Fab")
		)
		(pad "1" smd circle
			(at 0.40005 0 270)
			(size 0 0)
			(layers "B.Cu" "B.Mask" "B.Paste")
			(net "P12V_HSC_ADC_P")
		)
		(pad "2" smd circle
			(at -0.40005 0 270)
			(size 0 0)
			(layers "B.Cu" "B.Mask" "B.Paste")
			(net "P12V_HSC_SENSE2_R4_P")
		)
	)
	(footprint ""
		(layer "B.Cu")
		(at 103.25608 -359.070148 180)
		(property "Reference" "R2523"
			(at 0 0 0)
			(layer "B.SilkS")
			(hide yes)
			(effects
				(font
					(size 1.27 1.27)
				)
				(justify mirror)
			)
		)
		(property "Value" ""
			(at 0 0 0)
			(layer "B.Fab")
			(effects
				(font
					(size 1.27 1.27)
				)
				(justify mirror)
			)
		)
		(duplicate_pad_numbers_are_jumpers no)
		(fp_line
			(start 0.7874 0.4064)
			(end 0.7874 -0.4064)
			(stroke
				(width 0.1524)
				(type default)
			)
			(layer "B.SilkS")
		)
		(fp_line
			(start 0.7874 -0.4064)
			(end -0.7874 -0.4064)
			(stroke
				(width 0.1524)
				(type default)
			)
			(layer "B.SilkS")
		)
		(fp_line
			(start -0.7874 0.4064)
			(end 0.7874 0.4064)
			(stroke
				(width 0.1524)
				(type default)
			)
			(layer "B.SilkS")
		)
		(fp_line
			(start -0.7874 -0.4064)
			(end -0.7874 0.4064)
			(stroke
				(width 0.1524)
				(type default)
			)
			(layer "B.SilkS")
		)
		(fp_line
			(start 0.67945 0.3048)
			(end 0.67945 -0.305054)
			(stroke
				(width 0.1)
				(type default)
			)
			(layer "B.Fab")
		)
		(fp_line
			(start 0.67945 -0.305054)
			(end 0.12065 -0.305054)
			(stroke
				(width 0.1)
				(type default)
			)
			(layer "B.Fab")
		)
		(fp_line
			(start 0.12065 0.3048)
			(end 0.67945 0.3048)
			(stroke
				(width 0.1)
				(type default)
			)
			(layer "B.Fab")
		)
		(fp_line
			(start 0.12065 0.2794)
			(end 0.12065 0.3048)
			(stroke
				(width 0.1)
				(type default)
			)
			(layer "B.Fab")
		)
		(fp_line
			(start 0.12065 -0.2794)
			(end -0.12065 -0.2794)
			(stroke
				(width 0.1)
				(type default)
			)
			(layer "B.Fab")
		)
		(fp_line
			(start 0.12065 -0.305054)
			(end 0.12065 -0.2794)
			(stroke
				(width 0.1)
				(type default)
			)
			(layer "B.Fab")
		)
		(fp_line
			(start -0.120396 0.3048)
			(end -0.120396 0.2794)
			(stroke
				(width 0.1)
				(type default)
			)
			(layer "B.Fab")
		)
		(fp_line
			(start -0.120396 0.2794)
			(end 0.12065 0.2794)
			(stroke
				(width 0.1)
				(type default)
			)
			(layer "B.Fab")
		)
		(fp_line
			(start -0.12065 -0.2794)
			(end -0.12065 -0.3048)
			(stroke
				(width 0.1)
				(type default)
			)
			(layer "B.Fab")
		)
		(fp_line
			(start -0.12065 -0.3048)
			(end -0.67945 -0.3048)
			(stroke
				(width 0.1)
				(type default)
			)
			(layer "B.Fab")
		)
		(fp_line
			(start -0.67945 0.3048)
			(end -0.120396 0.3048)
			(stroke
				(width 0.1)
				(type default)
			)
			(layer "B.Fab")
		)
		(fp_line
			(start -0.67945 -0.3048)
			(end -0.67945 0.3048)
			(stroke
				(width 0.1)
				(type default)
			)
			(layer "B.Fab")
		)
		(pad "1" smd circle
			(at 0.40005 0)
			(size 0 0)
			(layers "B.Cu" "B.Mask" "B.Paste")
			(net "IRQ_PVCCIN_CPU1_VRHOT_R_N")
		)
		(pad "2" smd circle
			(at -0.40005 0)
			(size 0 0)
			(layers "B.Cu" "B.Mask" "B.Paste")
			(net "IRQ_PVCCIN_CPU1_VRHOT_N")
		)
	)
	(footprint ""
		(layer "B.Cu")
		(at 203.877926 -79.444342)
		(property "Reference" "C1826"
			(at 0 0 0)
			(layer "B.SilkS")
			(hide yes)
			(effects
				(font
					(size 1.27 1.27)
				)
				(justify mirror)
			)
		)
		(property "Value" ""
			(at 0 0 0)
			(layer "B.Fab")
			(effects
				(font
					(size 1.27 1.27)
				)
				(justify mirror)
			)
		)
		(duplicate_pad_numbers_are_jumpers no)
		(fp_line
			(start -0.7874 -0.4064)
			(end -0.7874 0.4064)
			(stroke
				(width 0.1524)
				(type default)
			)
			(layer "B.SilkS")
		)
		(fp_line
			(start -0.7874 0.4064)
			(end 0.7874 0.4064)
			(stroke
				(width 0.1524)
				(type default)
			)
			(layer "B.SilkS")
		)
		(fp_line
			(start 0.7874 -0.4064)
			(end -0.7874 -0.4064)
			(stroke
				(width 0.1524)
				(type default)
			)
			(layer "B.SilkS")
		)
		(fp_line
			(start 0.7874 0.4064)
			(end 0.7874 -0.4064)
			(stroke
				(width 0.1524)
				(type default)
			)
			(layer "B.SilkS")
		)
		(fp_line
			(start -0.67945 -0.3048)
			(end -0.67945 0.3048)
			(stroke
				(width 0.1)
				(type default)
			)
			(layer "B.Fab")
		)
		(fp_line
			(start -0.67945 0.3048)
			(end -0.120396 0.3048)
			(stroke
				(width 0.1)
				(type default)
			)
			(layer "B.Fab")
		)
		(fp_line
			(start -0.12065 -0.3048)
			(end -0.67945 -0.3048)
			(stroke
				(width 0.1)
				(type default)
			)
			(layer "B.Fab")
		)
		(fp_line
			(start -0.12065 -0.2794)
			(end -0.12065 -0.3048)
			(stroke
				(width 0.1)
				(type default)
			)
			(layer "B.Fab")
		)
		(fp_line
			(start -0.120396 0.2794)
			(end 0.12065 0.2794)
			(stroke
				(width 0.1)
				(type default)
			)
			(layer "B.Fab")
		)
		(fp_line
			(start -0.120396 0.3048)
			(end -0.120396 0.2794)
			(stroke
				(width 0.1)
				(type default)
			)
			(layer "B.Fab")
		)
		(fp_line
			(start 0.12065 -0.305054)
			(end 0.12065 -0.2794)
			(stroke
				(width 0.1)
				(type default)
			)
			(layer "B.Fab")
		)
		(fp_line
			(start 0.12065 -0.2794)
			(end -0.12065 -0.2794)
			(stroke
				(width 0.1)
				(type default)
			)
			(layer "B.Fab")
		)
		(fp_line
			(start 0.12065 0.2794)
			(end 0.12065 0.3048)
			(stroke
				(width 0.1)
				(type default)
			)
			(layer "B.Fab")
		)
		(fp_line
			(start 0.12065 0.3048)
			(end 0.67945 0.3048)
			(stroke
				(width 0.1)
				(type default)
			)
			(layer "B.Fab")
		)
		(fp_line
			(start 0.67945 -0.305054)
			(end 0.12065 -0.305054)
			(stroke
				(width 0.1)
				(type default)
			)
			(layer "B.Fab")
		)
		(fp_line
			(start 0.67945 0.3048)
			(end 0.67945 -0.305054)
			(stroke
				(width 0.1)
				(type default)
			)
			(layer "B.Fab")
		)
		(pad "1" smd circle
			(at 0.40005 0 180)
			(size 0 0)
			(layers "B.Cu" "B.Mask" "B.Paste")
			(net "P3V3_AUX")
		)
		(pad "2" smd circle
			(at -0.40005 0 180)
			(size 0 0)
			(layers "B.Cu" "B.Mask" "B.Paste")
			(net "GND")
		)
	)
	(footprint ""
		(layer "B.Cu")
		(at 11.80592 -400.030188)
		(property "Reference" ""
			(at 0 0 0)
			(layer "B.SilkS")
			(hide yes)
			(effects
				(font
					(size 1.27 1.27)
				)
				(justify mirror)
			)
		)
		(property "Value" ""
			(at 0 0 0)
			(layer "B.Fab")
			(effects
				(font
					(size 1.27 1.27)
				)
				(justify mirror)
			)
		)
		(duplicate_pad_numbers_are_jumpers no)
		(pad "1" smd circle
			(at 0 0 180)
			(size 0.9906 0.9906)
			(layers "B.Cu" "B.Mask" "B.Paste")
			(net "Net_288")
		)
		(zone
			(layer "B.Cu")
			(hatch none 0.5)
			(connect_pads
				(clearance 0)
			)
			(min_thickness 0.25)
			(keepout
				(tracks not_allowed)
				(vias allowed)
				(pads allowed)
				(copperpour not_allowed)
				(footprints allowed)
			)
			(placement
				(enabled no)
				(sheetname "")
			)
			(fill
				(thermal_gap 0.5)
				(thermal_bridge_width 0.5)
				(island_removal_mode 0)
			)
			(polygon
				(pts
					(arc
						(start 13.43152 -400.030188)
						(mid 10.18032 -400.030188)
						(end 13.43152 -400.030188)
					)
				)
			)
		)
	)
	(footprint ""
		(layer "B.Cu")
		(at 54.510178 -353.567492 90)
		(property "Reference" "PC406_P1_2"
			(at 0 0 90)
			(layer "B.SilkS")
			(hide yes)
			(effects
				(font
					(size 1.27 1.27)
				)
				(justify mirror)
			)
		)
		(property "Value" ""
			(at 0 0 90)
			(layer "B.Fab")
			(effects
				(font
					(size 1.27 1.27)
				)
				(justify mirror)
			)
		)
		(duplicate_pad_numbers_are_jumpers no)
		(fp_line
			(start 1.524 -0.762)
			(end -1.524 -0.762)
			(stroke
				(width 0.1524)
				(type default)
			)
			(layer "B.SilkS")
		)
		(fp_line
			(start -1.524 -0.762)
			(end -1.524 0.762)
			(stroke
				(width 0.1524)
				(type default)
			)
			(layer "B.SilkS")
		)
		(fp_line
			(start 1.524 0.762)
			(end 1.524 -0.762)
			(stroke
				(width 0.1524)
				(type default)
			)
			(layer "B.SilkS")
		)
		(fp_line
			(start -1.524 0.762)
			(end 1.524 0.762)
			(stroke
				(width 0.1524)
				(type default)
			)
			(layer "B.SilkS")
		)
		(fp_line
			(start 1.1049 -0.724916)
			(end 1.1049 0.724916)
			(stroke
				(width 0.1)
				(type default)
			)
			(layer "B.Fab")
		)
		(fp_line
			(start -1.1049 -0.724916)
			(end 1.1049 -0.724916)
			(stroke
				(width 0.1)
				(type default)
			)
			(layer "B.Fab")
		)
		(fp_line
			(start 1.1049 0.724916)
			(end -1.1049 0.724916)
			(stroke
				(width 0.1)
				(type default)
			)
			(layer "B.Fab")
		)
		(fp_line
			(start -1.1049 0.724916)
			(end -1.1049 -0.724916)
			(stroke
				(width 0.1)
				(type default)
			)
			(layer "B.Fab")
		)
		(pad "1" smd rect
			(at 0.889 0 90)
			(size 1.016 1.27)
			(layers "B.Cu" "B.Mask" "B.Paste")
			(net "SW_P12V_PVCCFA_EHV_FIVRA_CPU1_L")
		)
		(pad "2" smd rect
			(at -0.889 0 90)
			(size 1.016 1.27)
			(layers "B.Cu" "B.Mask" "B.Paste")
			(net "GND")
		)
	)
)
